(kicad_pcb
	(version 20260206)
	(generator "pcbnew")
	(generator_version "10.0")
	(general
		(thickness 1.6)
		(legacy_teardrops no)
	)
	(paper "A4")
	(title_block
		(title "12092022_DA0F0TMDCD0_F0T_Management_Board_D_brd_V3_OCP.brd")
		(comment 1 "Grand Teton / footprints 879-884 of 1440")
	)
	(layers
		(0 "F.Cu" signal "TOP")
		(4 "In1.Cu" signal "GND")
		(6 "In2.Cu" signal "IN1")
		(8 "In3.Cu" signal "GND1")
		(10 "In4.Cu" signal "IN2")
		(12 "In5.Cu" signal "VCC")
		(14 "In6.Cu" signal "VCC1")
		(16 "In7.Cu" signal "IN3")
		(18 "In8.Cu" signal "GND2")
		(20 "In9.Cu" signal "IN4")
		(22 "In10.Cu" signal "GND3")
		(2 "B.Cu" signal "BOTTOM")
		(9 "F.Adhes" user "F.Adhesive")
		(11 "B.Adhes" user "B.Adhesive")
		(13 "F.Paste" user "Package Geometry/Pastemask Top")
		(15 "B.Paste" user "Package Geometry/Pastemask Bottom")
		(5 "F.SilkS" user "Ref Des/Silkscreen Top")
		(7 "B.SilkS" user "Ref Des/Silkscreen Bottom")
		(1 "F.Mask" user "Board Geometry/Soldermask Top")
		(3 "B.Mask" user "Board Geometry/Soldermask Bottom")
		(17 "Dwgs.User" user "User.Drawings")
		(19 "Cmts.User" user "User.Comments")
		(21 "Eco1.User" user "User.Eco1")
		(23 "Eco2.User" user "User.Eco2")
		(25 "Edge.Cuts" user "Board Geometry/Outline")
		(27 "Margin" user)
		(31 "F.CrtYd" user "Package Geometry/Place Bound Top")
		(29 "B.CrtYd" user "Package Geometry/Place Bound Bottom")
		(35 "F.Fab" user "Ref Des/Assembly Top")
		(33 "B.Fab" user "Ref Des/Assembly Bottom")
	)
	(footprint ""
		(layer "B.Cu")
		(at 53.8734 -63.1952 -90)
		(property "Reference" "R722"
			(at 0 0 90)
			(layer "B.SilkS")
			(hide yes)
			(effects
				(font
					(size 1.27 1.27)
				)
				(justify mirror)
			)
		)
		(property "Value" ""
			(at 0 0 90)
			(layer "B.Fab")
			(effects
				(font
					(size 1.27 1.27)
				)
				(justify mirror)
			)
		)
		(duplicate_pad_numbers_are_jumpers no)
		(fp_line
			(start -0.7874 0.4064)
			(end 0.7874 0.4064)
			(stroke
				(width 0.1524)
				(type default)
			)
			(layer "B.SilkS")
		)
		(fp_line
			(start 0.7874 0.4064)
			(end 0.7874 -0.4064)
			(stroke
				(width 0.1524)
				(type default)
			)
			(layer "B.SilkS")
		)
		(fp_line
			(start -0.7874 -0.4064)
			(end -0.7874 0.4064)
			(stroke
				(width 0.1524)
				(type default)
			)
			(layer "B.SilkS")
		)
		(fp_line
			(start 0.7874 -0.4064)
			(end -0.7874 -0.4064)
			(stroke
				(width 0.1524)
				(type default)
			)
			(layer "B.SilkS")
		)
		(fp_line
			(start -0.67945 0.3048)
			(end -0.120396 0.3048)
			(stroke
				(width 0.1)
				(type default)
			)
			(layer "B.Fab")
		)
		(fp_line
			(start -0.120396 0.3048)
			(end -0.120396 0.2794)
			(stroke
				(width 0.1)
				(type default)
			)
			(layer "B.Fab")
		)
		(fp_line
			(start 0.12065 0.3048)
			(end 0.67945 0.3048)
			(stroke
				(width 0.1)
				(type default)
			)
			(layer "B.Fab")
		)
		(fp_line
			(start 0.67945 0.3048)
			(end 0.67945 -0.305054)
			(stroke
				(width 0.1)
				(type default)
			)
			(layer "B.Fab")
		)
		(fp_line
			(start -0.120396 0.2794)
			(end 0.12065 0.2794)
			(stroke
				(width 0.1)
				(type default)
			)
			(layer "B.Fab")
		)
		(fp_line
			(start 0.12065 0.2794)
			(end 0.12065 0.3048)
			(stroke
				(width 0.1)
				(type default)
			)
			(layer "B.Fab")
		)
		(fp_line
			(start -0.12065 -0.2794)
			(end -0.12065 -0.3048)
			(stroke
				(width 0.1)
				(type default)
			)
			(layer "B.Fab")
		)
		(fp_line
			(start 0.12065 -0.2794)
			(end -0.12065 -0.2794)
			(stroke
				(width 0.1)
				(type default)
			)
			(layer "B.Fab")
		)
		(fp_line
			(start -0.67945 -0.3048)
			(end -0.67945 0.3048)
			(stroke
				(width 0.1)
				(type default)
			)
			(layer "B.Fab")
		)
		(fp_line
			(start -0.12065 -0.3048)
			(end -0.67945 -0.3048)
			(stroke
				(width 0.1)
				(type default)
			)
			(layer "B.Fab")
		)
		(fp_line
			(start 0.12065 -0.305054)
			(end 0.12065 -0.2794)
			(stroke
				(width 0.1)
				(type default)
			)
			(layer "B.Fab")
		)
		(fp_line
			(start 0.67945 -0.305054)
			(end 0.12065 -0.305054)
			(stroke
				(width 0.1)
				(type default)
			)
			(layer "B.Fab")
		)
		(pad "1" smd circle
			(at 0.40005 0 90)
			(size 0 0)
			(layers "B.Cu" "B.Mask" "B.Paste")
			(net "FM_SLPS3_GF_R1_N")
		)
		(pad "2" smd circle
			(at -0.40005 0 90)
			(size 0 0)
			(layers "B.Cu" "B.Mask" "B.Paste")
			(net "FM_SLPS3_GF_N")
		)
	)
	(footprint ""
		(layer "B.Cu")
		(at 46.3804 -105.7783 90)
		(property "Reference" "C196"
			(at 0 0 90)
			(layer "B.SilkS")
			(hide yes)
			(effects
				(font
					(size 1.27 1.27)
				)
				(justify mirror)
			)
		)
		(property "Value" ""
			(at 0 0 90)
			(layer "B.Fab")
			(effects
				(font
					(size 1.27 1.27)
				)
				(justify mirror)
			)
		)
		(duplicate_pad_numbers_are_jumpers no)
		(fp_line
			(start 0.7874 -0.4064)
			(end -0.7874 -0.4064)
			(stroke
				(width 0.1524)
				(type default)
			)
			(layer "B.SilkS")
		)
		(fp_line
			(start -0.7874 -0.4064)
			(end -0.7874 0.4064)
			(stroke
				(width 0.1524)
				(type default)
			)
			(layer "B.SilkS")
		)
		(fp_line
			(start 0.7874 0.4064)
			(end 0.7874 -0.4064)
			(stroke
				(width 0.1524)
				(type default)
			)
			(layer "B.SilkS")
		)
		(fp_line
			(start -0.7874 0.4064)
			(end 0.7874 0.4064)
			(stroke
				(width 0.1524)
				(type default)
			)
			(layer "B.SilkS")
		)
		(fp_line
			(start 0.67945 -0.305054)
			(end 0.12065 -0.305054)
			(stroke
				(width 0.1)
				(type default)
			)
			(layer "B.Fab")
		)
		(fp_line
			(start 0.12065 -0.305054)
			(end 0.12065 -0.2794)
			(stroke
				(width 0.1)
				(type default)
			)
			(layer "B.Fab")
		)
		(fp_line
			(start -0.12065 -0.3048)
			(end -0.67945 -0.3048)
			(stroke
				(width 0.1)
				(type default)
			)
			(layer "B.Fab")
		)
		(fp_line
			(start -0.67945 -0.3048)
			(end -0.67945 0.3048)
			(stroke
				(width 0.1)
				(type default)
			)
			(layer "B.Fab")
		)
		(fp_line
			(start 0.12065 -0.2794)
			(end -0.12065 -0.2794)
			(stroke
				(width 0.1)
				(type default)
			)
			(layer "B.Fab")
		)
		(fp_line
			(start -0.12065 -0.2794)
			(end -0.12065 -0.3048)
			(stroke
				(width 0.1)
				(type default)
			)
			(layer "B.Fab")
		)
		(fp_line
			(start 0.12065 0.2794)
			(end 0.12065 0.3048)
			(stroke
				(width 0.1)
				(type default)
			)
			(layer "B.Fab")
		)
		(fp_line
			(start -0.120396 0.2794)
			(end 0.12065 0.2794)
			(stroke
				(width 0.1)
				(type default)
			)
			(layer "B.Fab")
		)
		(fp_line
			(start 0.67945 0.3048)
			(end 0.67945 -0.305054)
			(stroke
				(width 0.1)
				(type default)
			)
			(layer "B.Fab")
		)
		(fp_line
			(start 0.12065 0.3048)
			(end 0.67945 0.3048)
			(stroke
				(width 0.1)
				(type default)
			)
			(layer "B.Fab")
		)
		(fp_line
			(start -0.120396 0.3048)
			(end -0.120396 0.2794)
			(stroke
				(width 0.1)
				(type default)
			)
			(layer "B.Fab")
		)
		(fp_line
			(start -0.67945 0.3048)
			(end -0.120396 0.3048)
			(stroke
				(width 0.1)
				(type default)
			)
			(layer "B.Fab")
		)
		(pad "1" smd circle
			(at 0.40005 0 270)
			(size 0 0)
			(layers "B.Cu" "B.Mask" "B.Paste")
			(net "P3V3_RTC_AUX")
		)
		(pad "2" smd circle
			(at -0.40005 0 270)
			(size 0 0)
			(layers "B.Cu" "B.Mask" "B.Paste")
			(net "GND")
		)
	)
	(footprint ""
		(layer "B.Cu")
		(at 72.13346 -65.40627 90)
		(property "Reference" "L16"
			(at 0 0 90)
			(layer "B.SilkS")
			(hide yes)
			(effects
				(font
					(size 1.27 1.27)
				)
				(justify mirror)
			)
		)
		(property "Value" ""
			(at 0 0 90)
			(layer "B.Fab")
			(effects
				(font
					(size 1.27 1.27)
				)
				(justify mirror)
			)
		)
		(duplicate_pad_numbers_are_jumpers no)
		(fp_line
			(start 1.27 -0.5842)
			(end -1.27 -0.5842)
			(stroke
				(width 0.1524)
				(type default)
			)
			(layer "B.SilkS")
		)
		(fp_line
			(start 1.27 -0.5588)
			(end 1.27 -0.5842)
			(stroke
				(width 0.1524)
				(type default)
			)
			(layer "B.SilkS")
		)
		(fp_line
			(start 1.27 0.5842)
			(end 1.27 -0.5842)
			(stroke
				(width 0.1524)
				(type default)
			)
			(layer "B.SilkS")
		)
		(fp_line
			(start 0.127 0.5842)
			(end 0.127 -0.5842)
			(stroke
				(width 0.1524)
				(type default)
			)
			(layer "B.SilkS")
		)
		(fp_line
			(start -0.127 0.5842)
			(end -0.127 -0.5842)
			(stroke
				(width 0.1524)
				(type default)
			)
			(layer "B.SilkS")
		)
		(fp_line
			(start -1.27 0.5842)
			(end -1.27 -0.5842)
			(stroke
				(width 0.1524)
				(type default)
			)
			(layer "B.SilkS")
		)
		(fp_line
			(start -1.27 0.5842)
			(end 1.27 0.5842)
			(stroke
				(width 0.1524)
				(type default)
			)
			(layer "B.SilkS")
		)
		(fp_line
			(start 0.9144 -0.508)
			(end -0.9144 -0.508)
			(stroke
				(width 0.1)
				(type default)
			)
			(layer "B.Fab")
		)
		(fp_line
			(start -0.9144 -0.508)
			(end -0.9144 -0.406654)
			(stroke
				(width 0.1)
				(type default)
			)
			(layer "B.Fab")
		)
		(fp_line
			(start 1.194308 -0.406654)
			(end 0.9144 -0.406654)
			(stroke
				(width 0.1)
				(type default)
			)
			(layer "B.Fab")
		)
		(fp_line
			(start 0.9144 -0.406654)
			(end 0.9144 -0.508)
			(stroke
				(width 0.1)
				(type default)
			)
			(layer "B.Fab")
		)
		(fp_line
			(start -0.9144 -0.406654)
			(end -1.1938 -0.406654)
			(stroke
				(width 0.1)
				(type default)
			)
			(layer "B.Fab")
		)
		(fp_line
			(start -1.1938 -0.406654)
			(end -1.1938 0.4064)
			(stroke
				(width 0.1)
				(type default)
			)
			(layer "B.Fab")
		)
		(fp_line
			(start -0.9144 0.4064)
			(end -0.9144 0.508)
			(stroke
				(width 0.1)
				(type default)
			)
			(layer "B.Fab")
		)
		(fp_line
			(start -1.1938 0.4064)
			(end -0.9144 0.4064)
			(stroke
				(width 0.1)
				(type default)
			)
			(layer "B.Fab")
		)
		(fp_line
			(start 1.194308 0.406654)
			(end 1.194308 -0.406654)
			(stroke
				(width 0.1)
				(type default)
			)
			(layer "B.Fab")
		)
		(fp_line
			(start 0.9144 0.406654)
			(end 1.194308 0.406654)
			(stroke
				(width 0.1)
				(type default)
			)
			(layer "B.Fab")
		)
		(fp_line
			(start 0.9144 0.508)
			(end 0.9144 0.406654)
			(stroke
				(width 0.1)
				(type default)
			)
			(layer "B.Fab")
		)
		(fp_line
			(start -0.9144 0.508)
			(end 0.9144 0.508)
			(stroke
				(width 0.1)
				(type default)
			)
			(layer "B.Fab")
		)
		(pad "1" smd rect
			(at 0.7366 0)
			(size 0.7112 0.8128)
			(layers "B.Cu" "B.Mask" "B.Paste")
			(net "P1V8_AUX")
		)
		(pad "2" smd rect
			(at -0.7366 0)
			(size 0.7112 0.8128)
			(layers "B.Cu" "B.Mask" "B.Paste")
			(net "P1V8_STBY_DP_VCC18A")
		)
	)
	(footprint ""
		(layer "B.Cu")
		(at 58.7375 -63.2333 -90)
		(property "Reference" "R458"
			(at 0 0 90)
			(layer "B.SilkS")
			(hide yes)
			(effects
				(font
					(size 1.27 1.27)
				)
				(justify mirror)
			)
		)
		(property "Value" ""
			(at 0 0 90)
			(layer "B.Fab")
			(effects
				(font
					(size 1.27 1.27)
				)
				(justify mirror)
			)
		)
		(duplicate_pad_numbers_are_jumpers no)
		(fp_line
			(start -0.7874 0.4064)
			(end 0.7874 0.4064)
			(stroke
				(width 0.1524)
				(type default)
			)
			(layer "B.SilkS")
		)
		(fp_line
			(start 0.7874 0.4064)
			(end 0.7874 -0.4064)
			(stroke
				(width 0.1524)
				(type default)
			)
			(layer "B.SilkS")
		)
		(fp_line
			(start -0.7874 -0.4064)
			(end -0.7874 0.4064)
			(stroke
				(width 0.1524)
				(type default)
			)
			(layer "B.SilkS")
		)
		(fp_line
			(start 0.7874 -0.4064)
			(end -0.7874 -0.4064)
			(stroke
				(width 0.1524)
				(type default)
			)
			(layer "B.SilkS")
		)
		(fp_line
			(start -0.67945 0.3048)
			(end -0.120396 0.3048)
			(stroke
				(width 0.1)
				(type default)
			)
			(layer "B.Fab")
		)
		(fp_line
			(start -0.120396 0.3048)
			(end -0.120396 0.2794)
			(stroke
				(width 0.1)
				(type default)
			)
			(layer "B.Fab")
		)
		(fp_line
			(start 0.12065 0.3048)
			(end 0.67945 0.3048)
			(stroke
				(width 0.1)
				(type default)
			)
			(layer "B.Fab")
		)
		(fp_line
			(start 0.67945 0.3048)
			(end 0.67945 -0.305054)
			(stroke
				(width 0.1)
				(type default)
			)
			(layer "B.Fab")
		)
		(fp_line
			(start -0.120396 0.2794)
			(end 0.12065 0.2794)
			(stroke
				(width 0.1)
				(type default)
			)
			(layer "B.Fab")
		)
		(fp_line
			(start 0.12065 0.2794)
			(end 0.12065 0.3048)
			(stroke
				(width 0.1)
				(type default)
			)
			(layer "B.Fab")
		)
		(fp_line
			(start -0.12065 -0.2794)
			(end -0.12065 -0.3048)
			(stroke
				(width 0.1)
				(type default)
			)
			(layer "B.Fab")
		)
		(fp_line
			(start 0.12065 -0.2794)
			(end -0.12065 -0.2794)
			(stroke
				(width 0.1)
				(type default)
			)
			(layer "B.Fab")
		)
		(fp_line
			(start -0.67945 -0.3048)
			(end -0.67945 0.3048)
			(stroke
				(width 0.1)
				(type default)
			)
			(layer "B.Fab")
		)
		(fp_line
			(start -0.12065 -0.3048)
			(end -0.67945 -0.3048)
			(stroke
				(width 0.1)
				(type default)
			)
			(layer "B.Fab")
		)
		(fp_line
			(start 0.12065 -0.305054)
			(end 0.12065 -0.2794)
			(stroke
				(width 0.1)
				(type default)
			)
			(layer "B.Fab")
		)
		(fp_line
			(start 0.67945 -0.305054)
			(end 0.12065 -0.305054)
			(stroke
				(width 0.1)
				(type default)
			)
			(layer "B.Fab")
		)
		(pad "1" smd circle
			(at 0.40005 0 90)
			(size 0 0)
			(layers "B.Cu" "B.Mask" "B.Paste")
			(net "FM_DEBUG_PORT_PRSNT_R1_N")
		)
		(pad "2" smd circle
			(at -0.40005 0 90)
			(size 0 0)
			(layers "B.Cu" "B.Mask" "B.Paste")
			(net "FM_DEBUG_PORT_PRSNT_N")
		)
	)
	(footprint ""
		(layer "B.Cu")
		(at 46.21784 -24.1173 90)
		(property "Reference" "R295"
			(at 0 0 90)
			(layer "B.SilkS")
			(hide yes)
			(effects
				(font
					(size 1.27 1.27)
				)
				(justify mirror)
			)
		)
		(property "Value" ""
			(at 0 0 90)
			(layer "B.Fab")
			(effects
				(font
					(size 1.27 1.27)
				)
				(justify mirror)
			)
		)
		(duplicate_pad_numbers_are_jumpers no)
		(fp_line
			(start 0.7874 -0.4064)
			(end -0.7874 -0.4064)
			(stroke
				(width 0.1524)
				(type default)
			)
			(layer "B.SilkS")
		)
		(fp_line
			(start -0.7874 -0.4064)
			(end -0.7874 0.4064)
			(stroke
				(width 0.1524)
				(type default)
			)
			(layer "B.SilkS")
		)
		(fp_line
			(start 0.7874 0.4064)
			(end 0.7874 -0.4064)
			(stroke
				(width 0.1524)
				(type default)
			)
			(layer "B.SilkS")
		)
		(fp_line
			(start -0.7874 0.4064)
			(end 0.7874 0.4064)
			(stroke
				(width 0.1524)
				(type default)
			)
			(layer "B.SilkS")
		)
		(fp_line
			(start 0.67945 -0.305054)
			(end 0.12065 -0.305054)
			(stroke
				(width 0.1)
				(type default)
			)
			(layer "B.Fab")
		)
		(fp_line
			(start 0.12065 -0.305054)
			(end 0.12065 -0.2794)
			(stroke
				(width 0.1)
				(type default)
			)
			(layer "B.Fab")
		)
		(fp_line
			(start -0.12065 -0.3048)
			(end -0.67945 -0.3048)
			(stroke
				(width 0.1)
				(type default)
			)
			(layer "B.Fab")
		)
		(fp_line
			(start -0.67945 -0.3048)
			(end -0.67945 0.3048)
			(stroke
				(width 0.1)
				(type default)
			)
			(layer "B.Fab")
		)
		(fp_line
			(start 0.12065 -0.2794)
			(end -0.12065 -0.2794)
			(stroke
				(width 0.1)
				(type default)
			)
			(layer "B.Fab")
		)
		(fp_line
			(start -0.12065 -0.2794)
			(end -0.12065 -0.3048)
			(stroke
				(width 0.1)
				(type default)
			)
			(layer "B.Fab")
		)
		(fp_line
			(start 0.12065 0.2794)
			(end 0.12065 0.3048)
			(stroke
				(width 0.1)
				(type default)
			)
			(layer "B.Fab")
		)
		(fp_line
			(start -0.120396 0.2794)
			(end 0.12065 0.2794)
			(stroke
				(width 0.1)
				(type default)
			)
			(layer "B.Fab")
		)
		(fp_line
			(start 0.67945 0.3048)
			(end 0.67945 -0.305054)
			(stroke
				(width 0.1)
				(type default)
			)
			(layer "B.Fab")
		)
		(fp_line
			(start 0.12065 0.3048)
			(end 0.67945 0.3048)
			(stroke
				(width 0.1)
				(type default)
			)
			(layer "B.Fab")
		)
		(fp_line
			(start -0.120396 0.3048)
			(end -0.120396 0.2794)
			(stroke
				(width 0.1)
				(type default)
			)
			(layer "B.Fab")
		)
		(fp_line
			(start -0.67945 0.3048)
			(end -0.120396 0.3048)
			(stroke
				(width 0.1)
				(type default)
			)
			(layer "B.Fab")
		)
		(pad "1" smd circle
			(at 0.40005 0 270)
			(size 0 0)
			(layers "B.Cu" "B.Mask" "B.Paste")
			(net "P3V3_AUX")
		)
		(pad "2" smd circle
			(at -0.40005 0 270)
			(size 0 0)
			(layers "B.Cu" "B.Mask" "B.Paste")
			(net "DEBUG_PORT_PRSNT_BUF_R_EN")
		)
	)
	(footprint ""
		(layer "B.Cu")
		(at 16.764 -70.104 90)
		(property "Reference" "R299"
			(at 0 0 90)
			(layer "B.SilkS")
			(hide yes)
			(effects
				(font
					(size 1.27 1.27)
				)
				(justify mirror)
			)
		)
		(property "Value" ""
			(at 0 0 90)
			(layer "B.Fab")
			(effects
				(font
					(size 1.27 1.27)
				)
				(justify mirror)
			)
		)
		(duplicate_pad_numbers_are_jumpers no)
		(fp_line
			(start 0.7874 -0.4064)
			(end -0.7874 -0.4064)
			(stroke
				(width 0.1524)
				(type default)
			)
			(layer "B.SilkS")
		)
		(fp_line
			(start -0.7874 -0.4064)
			(end -0.7874 0.4064)
			(stroke
				(width 0.1524)
				(type default)
			)
			(layer "B.SilkS")
		)
		(fp_line
			(start 0.7874 0.4064)
			(end 0.7874 -0.4064)
			(stroke
				(width 0.1524)
				(type default)
			)
			(layer "B.SilkS")
		)
		(fp_line
			(start -0.7874 0.4064)
			(end 0.7874 0.4064)
			(stroke
				(width 0.1524)
				(type default)
			)
			(layer "B.SilkS")
		)
		(fp_line
			(start 0.67945 -0.305054)
			(end 0.12065 -0.305054)
			(stroke
				(width 0.1)
				(type default)
			)
			(layer "B.Fab")
		)
		(fp_line
			(start 0.12065 -0.305054)
			(end 0.12065 -0.2794)
			(stroke
				(width 0.1)
				(type default)
			)
			(layer "B.Fab")
		)
		(fp_line
			(start -0.12065 -0.3048)
			(end -0.67945 -0.3048)
			(stroke
				(width 0.1)
				(type default)
			)
			(layer "B.Fab")
		)
		(fp_line
			(start -0.67945 -0.3048)
			(end -0.67945 0.3048)
			(stroke
				(width 0.1)
				(type default)
			)
			(layer "B.Fab")
		)
		(fp_line
			(start 0.12065 -0.2794)
			(end -0.12065 -0.2794)
			(stroke
				(width 0.1)
				(type default)
			)
			(layer "B.Fab")
		)
		(fp_line
			(start -0.12065 -0.2794)
			(end -0.12065 -0.3048)
			(stroke
				(width 0.1)
				(type default)
			)
			(layer "B.Fab")
		)
		(fp_line
			(start 0.12065 0.2794)
			(end 0.12065 0.3048)
			(stroke
				(width 0.1)
				(type default)
			)
			(layer "B.Fab")
		)
		(fp_line
			(start -0.120396 0.2794)
			(end 0.12065 0.2794)
			(stroke
				(width 0.1)
				(type default)
			)
			(layer "B.Fab")
		)
		(fp_line
			(start 0.67945 0.3048)
			(end 0.67945 -0.305054)
			(stroke
				(width 0.1)
				(type default)
			)
			(layer "B.Fab")
		)
		(fp_line
			(start 0.12065 0.3048)
			(end 0.67945 0.3048)
			(stroke
				(width 0.1)
				(type default)
			)
			(layer "B.Fab")
		)
		(fp_line
			(start -0.120396 0.3048)
			(end -0.120396 0.2794)
			(stroke
				(width 0.1)
				(type default)
			)
			(layer "B.Fab")
		)
		(fp_line
			(start -0.67945 0.3048)
			(end -0.120396 0.3048)
			(stroke
				(width 0.1)
				(type default)
			)
			(layer "B.Fab")
		)
		(pad "1" smd circle
			(at 0.40005 0 270)
			(size 0 0)
			(layers "B.Cu" "B.Mask" "B.Paste")
			(net "P3V3_AUX")
		)
		(pad "2" smd circle
			(at -0.40005 0 270)
			(size 0 0)
			(layers "B.Cu" "B.Mask" "B.Paste")
			(net "SMB_DEBUG_AUX_LVC3_USB_R1_SDA")
		)
	)
)
